(kicad_pcb
	(version 20260206)
	(generator "pcbnew")
	(generator_version "10.0")
	(general
		(thickness 1.21888)
		(legacy_teardrops no)
	)
	(paper "A4")
	(title_block
		(title "timecard-v8 — TimeCard-DC-V8_EXP.PcbDoc")
		(comment 1 "Time Appliance Project (Time Card) / footprints 64-72 of 288")
	)
	(layers
		(0 "F.Cu" signal "TOP")
		(4 "In1.Cu" signal "SGND")
		(6 "In2.Cu" signal "IN1")
		(8 "In3.Cu" signal "IN2")
		(10 "In4.Cu" signal "SGND1")
		(2 "B.Cu" signal "BOTTOM")
		(9 "F.Adhes" user "F.Adhesive")
		(11 "B.Adhes" user "B.Adhesive")
		(13 "F.Paste" user "Top Paste")
		(15 "B.Paste" user "Bottom Paste")
		(5 "F.SilkS" user "Top Overlay")
		(7 "B.SilkS" user "Bottom Overlay")
		(1 "F.Mask" user "Top Solder")
		(3 "B.Mask" user "Bottom Solder")
		(17 "Dwgs.User" user "User.Drawings")
		(19 "Cmts.User" user "User.Comments")
		(21 "Eco1.User" user "User.Eco1")
		(23 "Eco2.User" user "User.Eco2")
		(25 "Edge.Cuts" user)
		(27 "Margin" user)
		(31 "F.CrtYd" user "Top Courtyard")
		(29 "B.CrtYd" user "Bottom Courtyard")
		(35 "F.Fab" user "Top Component Center")
		(33 "B.Fab" user "Bottom Component Center")
	)
	(footprint "Vault:FP-0603-L_1_6_0_2-W_0_8_0-MFG"
		(layer "F.Cu")
		(at 198.9261 89.1162 180)
		(property "Reference" "C20"
			(at -1.336 -0.346345 0)
			(unlocked yes)
			(layer "F.SilkS")
			(effects
				(font
					(size 0.762 0.762)
					(thickness 0.2286)
				)
				(justify left bottom)
			)
		)
		(property "Value" "10uF_16V_0603"
			(at -6.5525 -3.826045 0)
			(unlocked yes)
			(layer "F.SilkS")
			(hide yes)
			(effects
				(font
					(size 0.762 0.762)
					(thickness 0.2286)
				)
				(justify left bottom)
			)
		)
		(sheetname "POWER")
		(sheetfile "POWER.kicad_sch")
		(duplicate_pad_numbers_are_jumpers no)
		(fp_line
			(start 0.9 0.825)
			(end -0.9 0.825)
			(stroke
				(width 0.2)
				(type solid)
			)
			(layer "F.SilkS")
		)
		(fp_line
			(start 0.9 -0.825)
			(end -0.9 -0.825)
			(stroke
				(width 0.2)
				(type solid)
			)
			(layer "F.SilkS")
		)
		(fp_line
			(start 1.15 0.6)
			(end -1.15 0.6)
			(stroke
				(width 0.2)
				(type solid)
			)
			(layer "F.CrtYd")
		)
		(fp_line
			(start 1.15 -0.6)
			(end 1.15 0.6)
			(stroke
				(width 0.2)
				(type solid)
			)
			(layer "F.CrtYd")
		)
		(fp_line
			(start 1.15 -0.6)
			(end -1.15 -0.6)
			(stroke
				(width 0.2)
				(type solid)
			)
			(layer "F.CrtYd")
		)
		(fp_line
			(start -1.15 -0.6)
			(end -1.15 0.6)
			(stroke
				(width 0.2)
				(type solid)
			)
			(layer "F.CrtYd")
		)
		(fp_line
			(start 1.15 0.6)
			(end -1.15 0.6)
			(stroke
				(width 0.2)
				(type solid)
			)
			(layer "F.Fab")
		)
		(fp_line
			(start 1.15 -0.6)
			(end 1.15 0.6)
			(stroke
				(width 0.2)
				(type solid)
			)
			(layer "F.Fab")
		)
		(fp_line
			(start 1.15 -0.6)
			(end -1.15 -0.6)
			(stroke
				(width 0.2)
				(type solid)
			)
			(layer "F.Fab")
		)
		(fp_line
			(start 0.5 0)
			(end -0.5 0)
			(stroke
				(width 0.1)
				(type solid)
			)
			(layer "F.Fab")
		)
		(fp_line
			(start 0 -0.5)
			(end 0 0.5)
			(stroke
				(width 0.1)
				(type solid)
			)
			(layer "F.Fab")
		)
		(fp_line
			(start -1.15 -0.6)
			(end -1.15 0.6)
			(stroke
				(width 0.2)
				(type solid)
			)
			(layer "F.Fab")
		)
		(fp_text user "${REFERENCE}"
			(at -0.00001 0.09602 180)
			(unlocked yes)
			(layer "F.Fab")
			(effects
				(font
					(face "Arial")
					(size 0.63 0.63)
					(thickness 0.1)
				)
				(justify left bottom)
			)
		)
		(pad "1" smd rect
			(at -0.7 0 180)
			(size 0.7 0.7)
			(layers "F.Cu" "F.Mask" "F.Paste")
			(net "+3.3V")
			(solder_mask_margin 0)
			(solder_paste_margin 0)
		)
		(pad "2" smd rect
			(at 0.7 0 180)
			(size 0.7 0.7)
			(layers "F.Cu" "F.Mask" "F.Paste")
			(net "GND")
			(solder_mask_margin 0)
			(solder_paste_margin 0)
		)
	)
	(footprint "Vault:SOT143-4L"
		(layer "F.Cu")
		(at 71.8761 128.1162 90)
		(property "Reference" "D2"
			(at -2.926921 1.178595 0)
			(unlocked yes)
			(layer "F.SilkS")
			(effects
				(font
					(size 0.762 0.762)
					(thickness 0.2286)
				)
			)
		)
		(property "Value" "8240136"
			(at 2.6781 3.341871 90)
			(unlocked yes)
			(layer "F.SilkS")
			(hide yes)
			(effects
				(font
					(size 0.762 0.762)
					(thickness 0.2286)
				)
			)
		)
		(sheetname "USER_IO")
		(sheetfile "USER_IO.kicad_sch")
		(duplicate_pad_numbers_are_jumpers no)
		(fp_line
			(start 2.05 -1.7)
			(end 2.05 1.7)
			(stroke
				(width 0.2)
				(type solid)
			)
			(layer "F.SilkS")
		)
		(fp_line
			(start -2.05 -1.7)
			(end 2.05 -1.7)
			(stroke
				(width 0.2)
				(type solid)
			)
			(layer "F.SilkS")
		)
		(fp_line
			(start -2.05 -1.7)
			(end -2.05 1.675)
			(stroke
				(width 0.2)
				(type solid)
			)
			(layer "F.SilkS")
		)
		(fp_line
			(start -2.05 1.7)
			(end 2.05 1.7)
			(stroke
				(width 0.2)
				(type solid)
			)
			(layer "F.SilkS")
		)
		(fp_circle
			(center -2.404 -1.075)
			(end -2.15 -1.075)
			(stroke
				(width 0.2)
				(type solid)
			)
			(fill no)
			(layer "F.SilkS")
		)
		(pad "1" smd rect
			(at -1.1 -0.75 180)
			(size 1.4 1.4)
			(layers "F.Cu" "F.Mask" "F.Paste")
			(net "GND")
		)
		(pad "2" smd rect
			(at -1.1 0.95 180)
			(size 1 1.4)
			(layers "F.Cu" "F.Mask" "F.Paste")
			(net "NetAN4_1")
		)
		(pad "3" smd rect
			(at 1.1 0.95 180)
			(size 1 1.4)
			(layers "F.Cu" "F.Mask" "F.Paste")
			(net "NetAN3_1")
		)
		(pad "4" smd rect
			(at 1.1 -0.95 180)
			(size 1 1.4)
			(layers "F.Cu" "F.Mask" "F.Paste")
			(net "+3.3V")
		)
	)
	(footprint "Vault:CAPC1005X56X25NL10T15"
		(layer "F.Cu")
		(at 198.8261 91.0162)
		(property "Reference" "C19"
			(at 1.046 1.141655 180)
			(unlocked yes)
			(layer "F.SilkS")
			(effects
				(font
					(size 0.762 0.762)
					(thickness 0.2286)
				)
				(justify left bottom)
			)
		)
		(property "Value" "0.1uF_0402"
			(at 9.4735 -2.041355 0)
			(unlocked yes)
			(layer "F.SilkS")
			(hide yes)
			(effects
				(font
					(size 0.762 0.762)
					(thickness 0.2286)
				)
				(justify left bottom)
			)
		)
		(sheetname "POWER")
		(sheetfile "POWER.kicad_sch")
		(duplicate_pad_numbers_are_jumpers no)
		(pad "1" smd rect
			(at -0.44 0 90)
			(size 0.64 0.68)
			(layers "F.Cu" "F.Mask" "F.Paste")
			(net "GND")
		)
		(pad "2" smd rect
			(at 0.44 0 90)
			(size 0.64 0.68)
			(layers "F.Cu" "F.Mask" "F.Paste")
			(net "+3.3V")
		)
	)
	(footprint "Vault:RESC1005X40X25LL05T05"
		(layer "F.Cu")
		(at 234.2261 116.6162 180)
		(property "Reference" "R66"
			(at -0.7286 -1.026921 0)
			(unlocked yes)
			(layer "F.SilkS")
			(effects
				(font
					(size 0.762 0.762)
					(thickness 0.2286)
				)
			)
		)
		(property "Value" "0_1%_0402"
			(at -2.579871 6.66536 90)
			(unlocked yes)
			(layer "F.SilkS")
			(hide yes)
			(effects
				(font
					(size 0.762 0.762)
					(thickness 0.2286)
				)
			)
		)
		(sheetname "POWER")
		(sheetfile "POWER.kicad_sch")
		(duplicate_pad_numbers_are_jumpers no)
		(pad "1" smd rect
			(at -0.4 0 270)
			(size 0.45 0.45)
			(layers "F.Cu" "F.Mask" "F.Paste")
			(net "NetR66_1")
		)
		(pad "2" smd rect
			(at 0.4 0 270)
			(size 0.45 0.45)
			(layers "F.Cu" "F.Mask" "F.Paste")
			(net "GND")
		)
	)
	(footprint "Vault:FP-0402-L_1_0_1-W_0_5_0_1-IPC_C"
		(layer "F.Cu")
		(at 237.5261 64.7162 90)
		(property "Reference" "C93"
			(at 2.1714 1.073069 270)
			(unlocked yes)
			(layer "F.SilkS")
			(effects
				(font
					(size 0.762 0.762)
					(thickness 0.2286)
				)
			)
		)
		(property "Value" "0.1uF_25V_0402"
			(at -2.465551 9.839215 0)
			(unlocked yes)
			(layer "F.SilkS")
			(hide yes)
			(effects
				(font
					(size 0.762 0.762)
					(thickness 0.2286)
				)
			)
		)
		(sheetname "USBUart_DipSelects")
		(sheetfile "USBUart_DipSelects.kicad_sch")
		(duplicate_pad_numbers_are_jumpers no)
		(fp_line
			(start -0.65607 -0.7)
			(end 0.65607 -0.7)
			(stroke
				(width 0.2)
				(type solid)
			)
			(layer "F.SilkS")
		)
		(fp_line
			(start -0.65607 0.7)
			(end 0.65607 0.7)
			(stroke
				(width 0.2)
				(type solid)
			)
			(layer "F.SilkS")
		)
		(fp_line
			(start 0.75607 -0.4)
			(end 0.75607 0.4)
			(stroke
				(width 0.2)
				(type solid)
			)
			(layer "F.CrtYd")
		)
		(fp_line
			(start -0.75607 -0.4)
			(end 0.75607 -0.4)
			(stroke
				(width 0.2)
				(type solid)
			)
			(layer "F.CrtYd")
		)
		(fp_line
			(start -0.75607 -0.4)
			(end -0.75607 0.4)
			(stroke
				(width 0.2)
				(type solid)
			)
			(layer "F.CrtYd")
		)
		(fp_line
			(start -0.75607 0.4)
			(end 0.75607 0.4)
			(stroke
				(width 0.2)
				(type solid)
			)
			(layer "F.CrtYd")
		)
		(fp_line
			(start 0 -0.5)
			(end 0 0.5)
			(stroke
				(width 0.1)
				(type solid)
			)
			(layer "F.Fab")
		)
		(fp_line
			(start 0.75607 -0.4)
			(end 0.75607 0.4)
			(stroke
				(width 0.2)
				(type solid)
			)
			(layer "F.Fab")
		)
		(fp_line
			(start -0.75607 -0.4)
			(end 0.75607 -0.4)
			(stroke
				(width 0.2)
				(type solid)
			)
			(layer "F.Fab")
		)
		(fp_line
			(start -0.75607 -0.4)
			(end -0.75607 0.4)
			(stroke
				(width 0.2)
				(type solid)
			)
			(layer "F.Fab")
		)
		(fp_line
			(start -0.5 0)
			(end 0.5 0)
			(stroke
				(width 0.1)
				(type solid)
			)
			(layer "F.Fab")
		)
		(fp_line
			(start -0.75607 0.4)
			(end 0.75607 0.4)
			(stroke
				(width 0.2)
				(type solid)
			)
			(layer "F.Fab")
		)
		(fp_text user "${REFERENCE}"
			(at -0.00001 0.09601 90)
			(unlocked yes)
			(layer "F.Fab")
			(effects
				(font
					(face "Arial")
					(size 0.63 0.63)
					(thickness 0.1)
				)
				(justify left bottom)
			)
		)
		(pad "1" smd rect
			(at -0.36554 0 90)
			(size 0.58106 0.51213)
			(layers "F.Cu" "F.Mask" "F.Paste")
			(net "NetC92_1")
			(solder_mask_margin 0)
			(solder_paste_margin 0)
		)
		(pad "2" smd rect
			(at 0.36554 0 90)
			(size 0.58106 0.51213)
			(layers "F.Cu" "F.Mask" "F.Paste")
			(net "GND")
			(solder_mask_margin 0)
			(solder_paste_margin 0)
		)
	)
	(footprint "Vault:CAPC1005X55X25LL05T10"
		(layer "F.Cu")
		(at 231.4261 75.7162 -90)
		(property "Reference" "C88"
			(at -0.1714 4.826931 270)
			(unlocked yes)
			(layer "F.SilkS")
			(effects
				(font
					(size 0.762 0.762)
					(thickness 0.2286)
				)
			)
		)
		(property "Value" "47pF_50V_0402"
			(at -2.656031 9.61078 180)
			(unlocked yes)
			(layer "F.SilkS")
			(hide yes)
			(effects
				(font
					(size 0.762 0.762)
					(thickness 0.2286)
				)
			)
		)
		(sheetname "USBUart_DipSelects")
		(sheetfile "USBUart_DipSelects.kicad_sch")
		(duplicate_pad_numbers_are_jumpers no)
		(pad "1" smd rect
			(at -0.39 0)
			(size 0.52 0.56)
			(layers "F.Cu" "F.Mask" "F.Paste")
			(net "GND")
		)
		(pad "2" smd rect
			(at 0.39 0)
			(size 0.52 0.56)
			(layers "F.Cu" "F.Mask" "F.Paste")
			(net "FTDI_USB_R_N")
		)
	)
	(footprint "Vault:RESC1005X40X25LL05T05"
		(layer "F.Cu")
		(at 98.7261 88.0162 -90)
		(property "Reference" "R48"
			(at 0.5286 1.126931 270)
			(unlocked yes)
			(layer "F.SilkS")
			(effects
				(font
					(size 0.762 0.762)
					(thickness 0.2286)
				)
			)
		)
		(property "Value" "0_1%_0402"
			(at -2.579871 6.66536 180)
			(unlocked yes)
			(layer "F.SilkS")
			(hide yes)
			(effects
				(font
					(size 0.762 0.762)
					(thickness 0.2286)
				)
			)
		)
		(sheetname "GPS_IMU_SENSORS")
		(sheetfile "GPS_IMU_SENSORS.kicad_sch")
		(duplicate_pad_numbers_are_jumpers no)
		(pad "1" smd rect
			(at -0.4 0)
			(size 0.45 0.45)
			(layers "F.Cu" "F.Mask" "F.Paste")
			(net "NetP1_5")
		)
		(pad "2" smd rect
			(at 0.4 0)
			(size 0.45 0.45)
			(layers "F.Cu" "F.Mask" "F.Paste")
			(net "MAC_FREQ_CTRL")
		)
	)
	(footprint "Vault:FP-SML-LX0603IW-TR-MFG"
		(layer "F.Cu")
		(at 234.0261 135.3162 180)
		(property "Reference" "D20"
			(at -0.2286 1.273079 0)
			(unlocked yes)
			(layer "F.SilkS")
			(effects
				(font
					(size 0.762 0.762)
					(thickness 0.2286)
				)
			)
		)
		(property "Value" "SML-LX0603IW-TR"
			(at -3.519671 10.677135 90)
			(unlocked yes)
			(layer "F.SilkS")
			(hide yes)
			(effects
				(font
					(size 0.762 0.762)
					(thickness 0.2286)
				)
			)
		)
		(sheetname "POWER")
		(sheetfile "POWER.kicad_sch")
		(duplicate_pad_numbers_are_jumpers no)
		(fp_line
			(start 0.8 -0.75)
			(end -0.8 -0.75)
			(stroke
				(width 0.2)
				(type solid)
			)
			(layer "F.SilkS")
		)
		(fp_line
			(start 0.77934 0.73)
			(end -0.82066 0.73)
			(stroke
				(width 0.2)
				(type solid)
			)
			(layer "F.SilkS")
		)
		(fp_circle
			(center -1.725 0)
			(end -1.725 0.125)
			(stroke
				(width 0.25)
				(type solid)
			)
			(fill no)
			(layer "F.SilkS")
		)
		(fp_line
			(start 1.25 0.625)
			(end -1.25 0.625)
			(stroke
				(width 0.2)
				(type solid)
			)
			(layer "F.CrtYd")
		)
		(fp_line
			(start 1.25 -0.625)
			(end 1.25 0.625)
			(stroke
				(width 0.2)
				(type solid)
			)
			(layer "F.CrtYd")
		)
		(fp_line
			(start 1.25 -0.625)
			(end -1.25 -0.625)
			(stroke
				(width 0.2)
				(type solid)
			)
			(layer "F.CrtYd")
		)
		(fp_line
			(start -1.25 -0.625)
			(end -1.25 0.625)
			(stroke
				(width 0.2)
				(type solid)
			)
			(layer "F.CrtYd")
		)
		(fp_line
			(start 1.25 0.625)
			(end -1.25 0.625)
			(stroke
				(width 0.2)
				(type solid)
			)
			(layer "F.Fab")
		)
		(fp_line
			(start 1.25 -0.625)
			(end 1.25 0.625)
			(stroke
				(width 0.2)
				(type solid)
			)
			(layer "F.Fab")
		)
		(fp_line
			(start 1.25 -0.625)
			(end -1.25 -0.625)
			(stroke
				(width 0.2)
				(type solid)
			)
			(layer "F.Fab")
		)
		(fp_line
			(start 0.5 0)
			(end -0.5 0)
			(stroke
				(width 0.1)
				(type solid)
			)
			(layer "F.Fab")
		)
		(fp_line
			(start 0 -0.5)
			(end 0 0.5)
			(stroke
				(width 0.1)
				(type solid)
			)
			(layer "F.Fab")
		)
		(fp_line
			(start -1.25 -0.625)
			(end -1.25 0.625)
			(stroke
				(width 0.2)
				(type solid)
			)
			(layer "F.Fab")
		)
		(fp_text user "${REFERENCE}"
			(at 0.00001 0.28425 180)
			(unlocked yes)
			(layer "F.Fab")
			(effects
				(font
					(face "Arial")
					(size 0.63 0.63)
					(thickness 0.1)
				)
				(justify left bottom)
			)
		)
		(pad "1" smd rect
			(at -0.75 0 180)
			(size 0.8 0.8)
			(layers "F.Cu" "F.Mask" "F.Paste")
			(net "NetD20_1")
			(solder_mask_margin 0)
			(solder_paste_margin 0)
		)
		(pad "2" smd rect
			(at 0.75 0 180)
			(size 0.8 0.8)
			(layers "F.Cu" "F.Mask" "F.Paste")
			(net "+3.3V")
			(solder_mask_margin 0)
			(solder_paste_margin 0)
		)
	)
	(footprint "Vault:FP-D0008A-MFG"
		(layer "F.Cu")
		(at 203.1261 87.2162 -90)
		(property "Reference" "U2"
			(at 6.13379 -2.264855 90)
			(unlocked yes)
			(layer "F.SilkS")
			(effects
				(font
					(size 0.762 0.762)
					(thickness 0.2286)
				)
				(justify left bottom)
			)
		)
		(property "Value" "INA219BIDR"
			(at 9.427445 -10.9955 0)
			(unlocked yes)
			(layer "F.SilkS")
			(hide yes)
			(effects
				(font
					(size 0.762 0.762)
					(thickness 0.2286)
				)
				(justify left bottom)
			)
		)
		(sheetname "POWER")
		(sheetfile "POWER.kicad_sch")
		(duplicate_pad_numbers_are_jumpers no)
		(fp_line
			(start -1.5 2.5)
			(end -1.5 -2.5)
			(stroke
				(width 0.2)
				(type solid)
			)
			(layer "F.SilkS")
		)
		(fp_line
			(start 1.5 2.5)
			(end -1.5 2.5)
			(stroke
				(width 0.2)
				(type solid)
			)
			(layer "F.SilkS")
		)
		(fp_line
			(start 1.5 2.5)
			(end 1.5 -2.5)
			(stroke
				(width 0.2)
				(type solid)
			)
			(layer "F.SilkS")
		)
		(fp_line
			(start 1.5 -2.5)
			(end -1.5 -2.5)
			(stroke
				(width 0.2)
				(type solid)
			)
			(layer "F.SilkS")
		)
		(fp_circle
			(center -0.725 -1.725)
			(end -0.975 -1.725)
			(stroke
				(width 0.5)
				(type solid)
			)
			(fill no)
			(layer "F.SilkS")
		)
		(fp_circle
			(center -4.05 -1.905)
			(end -4.175 -1.905)
			(stroke
				(width 0.25)
				(type solid)
			)
			(fill no)
			(layer "F.SilkS")
		)
		(fp_line
			(start -3.575 2.75)
			(end -3.575 -2.75)
			(stroke
				(width 0.2)
				(type solid)
			)
			(layer "F.CrtYd")
		)
		(fp_line
			(start 3.575 2.75)
			(end -3.575 2.75)
			(stroke
				(width 0.2)
				(type solid)
			)
			(layer "F.CrtYd")
		)
		(fp_line
			(start 3.575 2.75)
			(end 3.575 -2.75)
			(stroke
				(width 0.2)
				(type solid)
			)
			(layer "F.CrtYd")
		)
		(fp_line
			(start 3.575 -2.75)
			(end -3.575 -2.75)
			(stroke
				(width 0.2)
				(type solid)
			)
			(layer "F.CrtYd")
		)
		(fp_line
			(start -3.575 2.75)
			(end -3.575 -2.75)
			(stroke
				(width 0.2)
				(type solid)
			)
			(layer "F.Fab")
		)
		(fp_line
			(start 3.575 2.75)
			(end -3.575 2.75)
			(stroke
				(width 0.2)
				(type solid)
			)
			(layer "F.Fab")
		)
		(fp_line
			(start 3.575 2.75)
			(end 3.575 -2.75)
			(stroke
				(width 0.2)
				(type solid)
			)
			(layer "F.Fab")
		)
		(fp_line
			(start 0 0.5)
			(end 0 -0.5)
			(stroke
				(width 0.1)
				(type solid)
			)
			(layer "F.Fab")
		)
		(fp_line
			(start 0.5 0)
			(end -0.5 0)
			(stroke
				(width 0.1)
				(type solid)
			)
			(layer "F.Fab")
		)
		(fp_line
			(start 3.575 -2.75)
			(end -3.575 -2.75)
			(stroke
				(width 0.2)
				(type solid)
			)
			(layer "F.Fab")
		)
		(fp_text user "${REFERENCE}"
			(at -0.00001 0.09602 270)
			(unlocked yes)
			(layer "F.Fab")
			(effects
				(font
					(face "Arial")
					(size 0.63 0.63)
					(thickness 0.1)
				)
				(justify left bottom)
			)
		)
		(pad "1" smd roundrect
			(at -2.7 -1.905 270)
			(size 1.55 0.6)
			(layers "F.Cu" "F.Mask" "F.Paste")
			(roundrect_rratio 0.085)
			(net "NetR64_1")
			(solder_mask_margin 0)
			(solder_paste_margin 0)
		)
		(pad "2" smd roundrect
			(at -2.7 -0.635 270)
			(size 1.55 0.6)
			(layers "F.Cu" "F.Mask" "F.Paste")
			(roundrect_rratio 0.085)
			(net "NetR62_1")
			(solder_mask_margin 0)
			(solder_paste_margin 0)
		)
		(pad "3" smd roundrect
			(at -2.7 0.635 270)
			(size 1.55 0.6)
			(layers "F.Cu" "F.Mask" "F.Paste")
			(roundrect_rratio 0.085)
			(net "SDA")
			(solder_mask_margin 0)
			(solder_paste_margin 0)
		)
		(pad "4" smd roundrect
			(at -2.7 1.905 270)
			(size 1.55 0.6)
			(layers "F.Cu" "F.Mask" "F.Paste")
			(roundrect_rratio 0.085)
			(net "SCL")
			(solder_mask_margin 0)
			(solder_paste_margin 0)
		)
		(pad "5" smd roundrect
			(at 2.7 1.905 270)
			(size 1.55 0.6)
			(layers "F.Cu" "F.Mask" "F.Paste")
			(roundrect_rratio 0.085)
			(net "+3.3V")
			(solder_mask_margin 0)
			(solder_paste_margin 0)
		)
		(pad "6" smd roundrect
			(at 2.7 0.635 270)
			(size 1.55 0.6)
			(layers "F.Cu" "F.Mask" "F.Paste")
			(roundrect_rratio 0.085)
			(net "GND")
			(solder_mask_margin 0)
			(solder_paste_margin 0)
		)
		(pad "7" smd roundrect
			(at 2.7 -0.635 270)
			(size 1.55 0.6)
			(layers "F.Cu" "F.Mask" "F.Paste")
			(roundrect_rratio 0.085)
			(net "+12V")
			(solder_mask_margin 0)
			(solder_paste_margin 0)
		)
		(pad "8" smd roundrect
			(at 2.7 -1.905 270)
			(size 1.55 0.6)
			(layers "F.Cu" "F.Mask" "F.Paste")
			(roundrect_rratio 0.085)
			(net "+12V_SENS")
			(solder_mask_margin 0)
			(solder_paste_margin 0)
		)
	)
)
